FILE_TYPE = CONNECTIVITY;
{Allegro Design Entry HDL 16.6-p007 (v16-6-112F) 10/10/2012}
"PAGE_NUMBER" = 115;
0"NC";
1"GND\g";
2"GND\g";
3"TP_USB2_P03_DN";
4"USB2_P02_DP";
5"USB2_P02_DN";
6"USB2_P01_DN";
7"USB2_P01_DP";
8"TP_USB2_P11_DN";
9"TP_USB3_P06_RXP";
10"TP_USB3_P06_RXN";
11"TP_USB3_P02_RXN";
12"TP_USB3_P02_RXP";
13"TP_USB3_P03_RXN";
14"TP_USB3_P03_RXP";
15"TP_USB3_P04_RXN";
16"TP_USB3_P04_RXP";
17"TP_USB3_P05_RXN";
18"TP_USB3_P05_RXP";
19"USB3_P01_RXN";
20"USB3_P01_RXP";
21"A_USB2_VBUS";
22"TP_PCH_RSVD55";
23"A_USB2_COMP";
24"TP_USB2_P06_DN";
25"TP_USB2_P03_DP";
26"USB_PCH_BMC_P4_DP";
27"USB_PCH_BMC_P4_DN";
28"USB2_PCH_BMC_P5_DN";
29"USB2_PCH_BMC_P5_DP";
30"TP_USB2_P10_DN";
31"TP_USB2_P12_DN";
32"TP_USB2_P13_DN";
33"TP_USB2_P14_DN";
34"TP_USB2_P07_DN";
35"TP_USB2_P8_DN";
36"TP_USB2_P9_DN";
37"TP_USB2_P10_DP";
38"TP_USB2_P11_DP";
39"TP_USB2_P12_DP";
40"TP_USB2_P13_DP";
41"TP_USB2_P14_DP";
42"TP_USB2_P06_DP";
43"TP_USB2_P07_DP";
44"TP_USB2_P8_DP";
45"TP_USB2_P9_DP";
46"TP_USB3_P02_TXN";
47"TP_USB3_P02_TXP";
48"TP_USB3_P03_TXN";
49"TP_USB3_P03_TXP";
50"TP_USB3_P04_TXN";
51"TP_USB3_P04_TXP";
52"TP_USB3_P05_TXN";
53"TP_USB3_P05_TXP";
54"TP_USB3_P06_TXN";
55"TP_USB3_P06_TXP";
56"USB3_P01_TXN";
57"USB3_P01_TXP";
%"RES"
"2","(-5425,1775)","0","mstr_discrete","I114";
;
CDS_SEC"1"
CDS_LOCATION"R8B32"
SEC_TYPE"0402"
CDS_LIB"mstr_discrete"
SEC"1"
WATTAGE"1/16W"
MATERIAL"CHIP"
PACK_TYPE"0402"
TOLERANCE"1%"
VALUE"10.0K"
PART_NUMBER"G21796-016"
LOCATION"R8B32";
"A"
$PN"1"21;
"B"
$PN"2"1;
%"GND"
"1","(-5425,1550)","0","mstr_symbols","I115";
;
HDL_POWER"GND"
BODY_TYPE"PLUMBING"
SIZE"1B"
CDS_LIB"mstr_symbols"
VOLTAGE"0.0V";
"A\NAC"1;
%"LBG_CORE_QAT_EXT_D"
"2","(-4000,2500)","0","mstr_u_proc","I74";
;
CDS_SEC"2"
ROOM"SB"
CDS_LOCATION"U7C1"
BOM_COST"SB"
CDS_LIB"mstr_u_proc"
SEC"2"
SEC_TYPE"BGA1"
PACK_TYPE"BGA1"
MATERIAL"IC"
PART_NUMBER"H91415-002"
LOCATION"U7C1";
"USB3_6_TXP"
$PN"BM61"55;
"USB3_6_TXN"
$PN"BL59"54;
"USB3_6_RXP"
$PN"BD70"9;
"USB3_6_RXN"
$PN"BD72"10;
"USB3_5_TXP"
$PN"BJ59"53;
"USB3_5_TXN"
$PN"BK58"52;
"USB3_5_RXP"
$PN"BE69"18;
"USB3_5_RXN"
$PN"BE71"17;
"USB3_4_TXP"
$PN"BG56"51;
"USB3_4_TXN"
$PN"BH58"50;
"USB3_4_RXP"
$PN"BF70"16;
"USB3_4_RXN"
$PN"BF72"15;
"USB3_3_TXP"
$PN"BN56"49;
"USB3_3_TXN"
$PN"BM54"48;
"USB3_3_RXP"
$PN"BH69"14;
"USB3_3_RXN"
$PN"BH71"13;
"USB3_2_TXP"
$PN"BJ56"47;
"USB3_2_TXN"
$PN"BL56"46;
"USB3_2_RXP"
$PN"BJ70"12;
"USB3_2_RXN"
$PN"BJ72"11;
"USB3_1_TXP"
$PN"BK54"57;
"USB3_1_TXN"
$PN"BL52"56;
"USB3_1_RXP"
$PN"BK69"20;
"USB3_1_RXN"
$PN"BK71"19;
"USB2_VBUS"
$PN"BR67"21;
"USB2_COMP"
$PN"BN70"23;
"USB2P_9"
$PN"BV55"45;
"USB2P_8"
$PN"BV64"44;
"USB2P_7"
$PN"BW57"43;
"USB2P_6"
$PN"BW63"42;
"USB2P_5"
$PN"BV58"29;
"USB2P_4"
$PN"BV62"26;
"USB2P_3"
$PN"BW59"25;
"USB2P_2"
$PN"BW61"4;
"USB2P_14"
$PN"BU67"41;
"USB2P_13"
$PN"BV53"40;
"USB2P_12"
$PN"BV66"39;
"USB2P_11"
$PN"BW54"38;
"USB2P_10"
$PN"BU65"37;
"USB2P_1"
$PN"BV60"7;
"USB2N_9"
$PN"BY55"36;
"USB2N_8"
$PN"BY64"35;
"USB2N_7"
$PN"CA57"34;
"USB2N_6"
$PN"CA63"24;
"USB2N_5"
$PN"BY58"28;
"USB2N_4"
$PN"BY62"27;
"USB2N_3"
$PN"CA59"3;
"USB2N_2"
$PN"CA61"5;
"USB2N_14"
$PN"BW68"33;
"USB2N_13"
$PN"BY53"32;
"USB2N_12"
$PN"BW67"31;
"USB2N_11"
$PN"CA54"8;
"USB2N_10"
$PN"BW65"30;
"USB2N_1"
$PN"BY60"6;
"RSVD<55>"
$PN"BN68"22;
%"RES"
"2","(-5750,1775)","0","mstr_discrete","I90";
;
CDS_SEC"1"
ROOM"SB"
CDS_LIB"mstr_discrete"
SEC_TYPE"0402"
SEC"1"
CDS_LOCATION"R8B9"
WATTAGE"1/16W"
MATERIAL"CHIP"
PACK_TYPE"0402"
TOLERANCE"1%"
VALUE"113"
PART_NUMBER"G21796-341"
LOCATION"R8B9";
"A"
$PN"1"23;
"B"
$PN"2"2;
%"GND"
"1","(-5750,1550)","0","mstr_symbols","I91";
;
HDL_POWER"GND"
BODY_TYPE"PLUMBING"
CDS_LIB"mstr_symbols"
SIZE"1B"
VOLTAGE"0.0V";
"A\NAC"2;
END.
